# BASEBOARD_FAB2 (Tioga Pass) — schematic netlist excerpt (pin names and nets, part order shuffled) for the footprints in the layout excerpt that follows; sources: Cadence DE-HDL packaged netlist, KiCad conversion of Wiwynn_Tioga_Pass_MB.brd

CF15  SC22P50V2JN-4GP  5%  pkg SMD-BCG  page 215 : \1\ = VR_PVDDQ_ABC_AIREF1 ; \2\ = ISENSE_PVDDQ_ABC_PH1_IMON
R9R8  RES  20.0 1% CHIP  pkg 0402  page 167 : A = SMB_SENSOR_TMP421_2_SDA ; B = SMB_SENSOR_STBY_LVC3_SDA
CT27  CAP  1000PF 50V 10% X7R  pkg 0402LF  page 207 : A = VR_PVCCIN_CPU1_PHASE2 ; B = VR_PVCCIN_CPU1_PHASE2_RC

(kicad_pcb
	(version 20260206)
	(generator "pcbnew")
	(generator_version "10.0")
	(general
		(thickness 1.6)
		(legacy_teardrops no)
	)
	(paper "A4")
	(title_block
		(title "Wiwynn_Tioga_Pass_MB.brd")
		(comment 1 "Tioga Pass / footprints 2216-2218 of 4770")
	)
	(layers
		(0 "F.Cu" signal "TOP")
		(4 "In1.Cu" signal "L2GND")
		(6 "In2.Cu" signal "L3")
		(8 "In3.Cu" signal "L4GND")
		(10 "In4.Cu" signal "L5")
		(12 "In5.Cu" signal "L6GND")
		(14 "In6.Cu" signal "L7VCC")
		(16 "In7.Cu" signal "L8VCC")
		(18 "In8.Cu" signal "L9GND")
		(20 "In9.Cu" signal "L10")
		(22 "In10.Cu" signal "L11GND")
		(24 "In11.Cu" signal "L12")
		(26 "In12.Cu" signal "L13GND")
		(2 "B.Cu" signal "BOTTOM")
		(9 "F.Adhes" user "F.Adhesive")
		(11 "B.Adhes" user "B.Adhesive")
		(13 "F.Paste" user "Package Geometry/Pastemask Top")
		(15 "B.Paste" user "Package Geometry/Pastemask Bottom")
		(5 "F.SilkS" user "Ref Des/Silkscreen Top")
		(7 "B.SilkS" user "Ref Des/Silkscreen Bottom")
		(1 "F.Mask" user "Board Geometry/Soldermask Top")
		(3 "B.Mask" user "Board Geometry/Soldermask Bottom")
		(17 "Dwgs.User" user "User.Drawings")
		(19 "Cmts.User" user "User.Comments")
		(21 "Eco1.User" user "User.Eco1")
		(23 "Eco2.User" user "User.Eco2")
		(25 "Edge.Cuts" user "Board Geometry/Outline")
		(27 "Margin" user)
		(31 "F.CrtYd" user "Package Geometry/Place Bound Top")
		(29 "B.CrtYd" user "Package Geometry/Place Bound Bottom")
		(35 "F.Fab" user "Ref Des/Assembly Top")
		(33 "B.Fab" user "Ref Des/Assembly Bottom")
	)
	(footprint ""
		(layer "F.Cu")
		(at 2.032 -75.057 180)
		(property "Reference" "R9R8"
			(at 0 0 180)
			(layer "F.SilkS")
			(hide yes)
			(effects
				(font
					(size 1.27 1.27)
				)
			)
		)
		(property "Value" ""
			(at 0 0 180)
			(layer "F.Fab")
			(effects
				(font
					(size 1.27 1.27)
				)
			)
		)
		(duplicate_pad_numbers_are_jumpers no)
		(fp_poly
			(pts
				(xy -0.2794 -0.1016) (xy 0.2794 -0.1016) (xy 0.2794 0.9906) (xy -0.2794 0.9906)
			)
			(stroke
				(width 0)
				(type default)
			)
			(fill no)
			(layer "F.CrtYd")
		)
		(fp_line
			(start 0.2794 0.9906)
			(end 0.2794 -0.1016)
			(stroke
				(width 0.1)
				(type default)
			)
			(layer "F.Fab")
		)
		(fp_line
			(start 0.2794 -0.1016)
			(end -0.2794 -0.1016)
			(stroke
				(width 0.1)
				(type default)
			)
			(layer "F.Fab")
		)
		(fp_line
			(start -0.2794 0.9906)
			(end 0.2794 0.9906)
			(stroke
				(width 0.1)
				(type default)
			)
			(layer "F.Fab")
		)
		(fp_line
			(start -0.2794 -0.1016)
			(end -0.2794 0.9906)
			(stroke
				(width 0.1)
				(type default)
			)
			(layer "F.Fab")
		)
		(pad "1" smd rect
			(at 0 0 180)
			(size 0.508 0.508)
			(layers "F.Cu" "F.Mask" "F.Paste")
			(net "SMB_SENSOR_TMP421_2_SDA")
		)
		(pad "2" smd rect
			(at 0 0.889 180)
			(size 0.508 0.508)
			(layers "F.Cu" "F.Mask" "F.Paste")
			(net "SMB_SENSOR_STBY_LVC3_SDA")
		)
		(zone
			(layer "F.Cu")
			(hatch none 0.5)
			(connect_pads
				(clearance 0)
			)
			(min_thickness 0.25)
			(keepout
				(tracks not_allowed)
				(vias allowed)
				(pads allowed)
				(copperpour not_allowed)
				(footprints allowed)
			)
			(placement
				(enabled no)
				(sheetname "")
			)
			(fill
				(thermal_gap 0.5)
				(thermal_bridge_width 0.5)
				(island_removal_mode 0)
			)
			(polygon
				(pts
					(xy 2.286 -75.692) (xy 1.778 -75.692) (xy 1.778 -75.311) (xy 2.286 -75.311)
				)
			)
		)
		(zone
			(layer "F.Cu")
			(hatch none 0.5)
			(connect_pads
				(clearance 0)
			)
			(min_thickness 0.25)
			(keepout
				(tracks allowed)
				(vias not_allowed)
				(pads allowed)
				(copperpour not_allowed)
				(footprints allowed)
			)
			(placement
				(enabled no)
				(sheetname "")
			)
			(fill
				(thermal_gap 0.5)
				(thermal_bridge_width 0.5)
				(island_removal_mode 0)
			)
			(polygon
				(pts
					(xy 2.286 -75.311) (xy 1.778 -75.311) (xy 1.778 -75.692) (xy 2.286 -75.692)
				)
			)
		)
	)
	(footprint ""
		(layer "F.Cu")
		(at 38.91534 -61.090048 -90)
		(property "Reference" "CT27"
			(at -0.8382 -0.67818 270)
			(unlocked yes)
			(layer "F.SilkS")
			(effects
				(font
					(size 0.4064 0.254)
					(thickness 0.1524)
				)
				(justify left)
			)
		)
		(property "Value" ""
			(at 0 0 270)
			(layer "F.Fab")
			(effects
				(font
					(size 1.27 1.27)
				)
			)
		)
		(duplicate_pad_numbers_are_jumpers no)
		(fp_poly
			(pts
				(xy 0.3048 -0.1016) (xy 0.3048 0.9906) (xy -0.3048 0.9906) (xy -0.3048 -0.1016)
			)
			(stroke
				(width 0)
				(type default)
			)
			(fill no)
			(layer "F.CrtYd")
		)
		(fp_line
			(start -0.3048 0.9906)
			(end 0.3048 0.9906)
			(stroke
				(width 0.1)
				(type default)
			)
			(layer "F.Fab")
		)
		(fp_line
			(start 0.3048 0.9906)
			(end 0.3048 -0.1016)
			(stroke
				(width 0.1)
				(type default)
			)
			(layer "F.Fab")
		)
		(fp_line
			(start -0.3048 -0.1016)
			(end -0.3048 0.9906)
			(stroke
				(width 0.1)
				(type default)
			)
			(layer "F.Fab")
		)
		(fp_line
			(start 0.3048 -0.1016)
			(end -0.3048 -0.1016)
			(stroke
				(width 0.1)
				(type default)
			)
			(layer "F.Fab")
		)
		(pad "1" smd rect
			(at 0 0 270)
			(size 0.508 0.508)
			(layers "F.Cu" "F.Mask" "F.Paste")
			(net "VR_PVCCIN_CPU1_PHASE2")
		)
		(pad "2" smd rect
			(at 0 0.889 270)
			(size 0.508 0.508)
			(layers "F.Cu" "F.Mask" "F.Paste")
			(net "VR_PVCCIN_CPU1_PHASE2_RC")
		)
		(zone
			(layer "F.Cu")
			(hatch none 0.5)
			(connect_pads
				(clearance 0)
			)
			(min_thickness 0.25)
			(keepout
				(tracks not_allowed)
				(vias allowed)
				(pads allowed)
				(copperpour not_allowed)
				(footprints allowed)
			)
			(placement
				(enabled no)
				(sheetname "")
			)
			(fill
				(thermal_gap 0.5)
				(thermal_bridge_width 0.5)
				(island_removal_mode 0)
			)
			(polygon
				(pts
					(xy 38.28034 -61.344048) (xy 38.28034 -60.836048) (xy 38.66134 -60.836048) (xy 38.66134 -61.344048)
				)
			)
		)
		(zone
			(layer "F.Cu")
			(hatch none 0.5)
			(connect_pads
				(clearance 0)
			)
			(min_thickness 0.25)
			(keepout
				(tracks allowed)
				(vias not_allowed)
				(pads allowed)
				(copperpour not_allowed)
				(footprints allowed)
			)
			(placement
				(enabled no)
				(sheetname "")
			)
			(fill
				(thermal_gap 0.5)
				(thermal_bridge_width 0.5)
				(island_removal_mode 0)
			)
			(polygon
				(pts
					(xy 38.66134 -61.344048) (xy 38.66134 -60.836048) (xy 38.28034 -60.836048) (xy 38.28034 -61.344048)
				)
			)
		)
	)
	(footprint ""
		(layer "F.Cu")
		(at 342.802464 -11.013694 90)
		(property "Reference" "CF15"
			(at 0 0 90)
			(layer "F.SilkS")
			(hide yes)
			(effects
				(font
					(size 1.27 1.27)
				)
			)
		)
		(property "Value" "*"
			(at 1.1811 -2.8194 90)
			(unlocked yes)
			(layer "F.Fab")
			(hide yes)
			(effects
				(font
					(size 1.27 1.016)
					(thickness 0.1524)
				)
			)
		)
		(property "Device Type" "SC22P50V2JN-4GP_SMD-BCG-SC22P5A"
			(at 1.1811 -4.3434 90)
			(unlocked yes)
			(layer "F.Fab")
			(hide yes)
			(effects
				(font
					(size 1.27 1.016)
					(thickness 0.1524)
				)
			)
		)
		(duplicate_pad_numbers_are_jumpers no)
		(fp_rect
			(start -0.4318 0.9525)
			(end 0.4318 -0.9525)
			(stroke
				(width 0)
				(type default)
			)
			(fill no)
			(layer "F.CrtYd")
		)
		(fp_rect
			(start -0.4318 0.9525)
			(end 0.4318 -0.9525)
			(stroke
				(width 0)
				(type default)
			)
			(fill no)
			(layer "F.Fab")
		)
		(pad "1" smd custom
			(at 0 -0.4445 90)
			(size 0.1524 0.1524)
			(layers "F.Cu" "F.Mask" "F.Paste")
			(net "VR_PVDDQ_ABC_AIREF1")
			(options
				(clearance outline)
				(anchor circle)
			)
			(primitives
				(gr_poly
					(pts
						(arc
							(start 0.3048 -0.2032)
							(mid 0.275042 -0.275042)
							(end 0.2032 -0.3048)
						)
						(arc
							(start -0.2032 -0.3048)
							(mid -0.275042 -0.275042)
							(end -0.3048 -0.2032)
						)
						(arc
							(start -0.3048 0.2032)
							(mid -0.275042 0.275042)
							(end -0.2032 0.3048)
						)
						(arc
							(start 0.2032 0.3048)
							(mid 0.275042 0.275042)
							(end 0.3048 0.2032)
						)
					)
					(width 0)
					(fill yes)
				)
			)
		)
		(pad "2" smd custom
			(at 0 0.4445 90)
			(size 0.1524 0.1524)
			(layers "F.Cu" "F.Mask" "F.Paste")
			(net "ISENSE_PVDDQ_ABC_PH1_IMON")
			(options
				(clearance outline)
				(anchor circle)
			)
			(primitives
				(gr_poly
					(pts
						(arc
							(start 0.3048 -0.2032)
							(mid 0.275042 -0.275042)
							(end 0.2032 -0.3048)
						)
						(arc
							(start -0.2032 -0.3048)
							(mid -0.275042 -0.275042)
							(end -0.3048 -0.2032)
						)
						(arc
							(start -0.3048 0.2032)
							(mid -0.275042 0.275042)
							(end -0.2032 0.3048)
						)
						(arc
							(start 0.2032 0.3048)
							(mid 0.275042 0.275042)
							(end 0.3048 0.2032)
						)
					)
					(width 0)
					(fill yes)
				)
			)
		)
	)
)
